(kicad_pcb
	(version 20260206)
	(generator "pcbnew")
	(generator_version "10.0")
	(general
		(thickness 1.6)
		(legacy_teardrops no)
	)
	(paper "A4")
	(title_block
		(title "baseboard — 13948-1b.1110WZS1818.brd")
		(comment 1 "Honey Badger (Wiwynn) / footprints 697-704 of 2523")
	)
	(layers
		(0 "F.Cu" signal "TOP")
		(4 "In1.Cu" signal "L2GND")
		(6 "In2.Cu" signal "L3")
		(8 "In3.Cu" signal "L4VCC")
		(10 "In4.Cu" signal "L5VCC")
		(12 "In5.Cu" signal "L6")
		(14 "In6.Cu" signal "L7GND")
		(2 "B.Cu" signal "BOTTOM")
		(9 "F.Adhes" user "F.Adhesive")
		(11 "B.Adhes" user "B.Adhesive")
		(13 "F.Paste" user "Package Geometry/Pastemask Top")
		(15 "B.Paste" user "Package Geometry/Pastemask Bottom")
		(5 "F.SilkS" user "Ref Des/Silkscreen Top")
		(7 "B.SilkS" user "Ref Des/Silkscreen Bottom")
		(1 "F.Mask" user "Board Geometry/Soldermask Top")
		(3 "B.Mask" user "Board Geometry/Soldermask Bottom")
		(17 "Dwgs.User" user "User.Drawings")
		(19 "Cmts.User" user "User.Comments")
		(21 "Eco1.User" user "User.Eco1")
		(23 "Eco2.User" user "User.Eco2")
		(25 "Edge.Cuts" user "Board Geometry/Outline")
		(27 "Margin" user)
		(31 "F.CrtYd" user "Package Geometry/Place Bound Top")
		(29 "B.CrtYd" user "Package Geometry/Place Bound Bottom")
		(35 "F.Fab" user "Ref Des/Assembly Top")
		(33 "B.Fab" user "Ref Des/Assembly Bottom")
	)
	(footprint ""
		(layer "F.Cu")
		(at 95.70085 -102.56012 -90)
		(property "Reference" "SR788"
			(at 0 0 270)
			(layer "F.SilkS")
			(hide yes)
			(effects
				(font
					(size 1.27 1.27)
				)
			)
		)
		(property "Value" "0R2J-2-GP"
			(at 0.064008 -3.993896 270)
			(unlocked yes)
			(layer "F.Fab")
			(hide yes)
			(effects
				(font
					(size 1.016 1.016)
					(thickness 0.1524)
				)
			)
		)
		(property "Device Type" "R402H16"
			(at 0.064008 -5.517896 270)
			(unlocked yes)
			(layer "F.Fab")
			(hide yes)
			(effects
				(font
					(size 1.016 1.016)
					(thickness 0.1524)
				)
			)
		)
		(duplicate_pad_numbers_are_jumpers no)
		(fp_line
			(start -0.508 -0.9398)
			(end -0.508 0.9398)
			(stroke
				(width 0.1524)
				(type default)
			)
			(layer "F.SilkS")
		)
		(fp_line
			(start 0.508 -0.9398)
			(end -0.508 -0.9398)
			(stroke
				(width 0.1524)
				(type default)
			)
			(layer "F.SilkS")
		)
		(fp_rect
			(start -0.508 0.9398)
			(end 0.508 -0.9398)
			(stroke
				(width 0)
				(type default)
			)
			(fill no)
			(layer "F.CrtYd")
		)
		(fp_rect
			(start -0.508 0.9398)
			(end 0.508 -0.9398)
			(stroke
				(width 0)
				(type default)
			)
			(fill no)
			(layer "F.Fab")
		)
		(pad "1" smd custom
			(at 0 -0.4445 270)
			(size 0.1397 0.1397)
			(layers "F.Cu" "F.Mask" "F.Paste")
			(net "SDB_R_RX")
			(options
				(clearance outline)
				(anchor circle)
			)
			(primitives
				(gr_poly
					(pts
						(arc
							(start -0.1778 -0.2794)
							(mid -0.249642 -0.249642)
							(end -0.2794 -0.1778)
						)
						(arc
							(start -0.2794 0.1778)
							(mid -0.249642 0.249642)
							(end -0.1778 0.2794)
						)
						(arc
							(start 0.1778 0.2794)
							(mid 0.249642 0.249642)
							(end 0.2794 0.1778)
						)
						(arc
							(start 0.2794 -0.1778)
							(mid 0.249642 -0.249642)
							(end 0.1778 -0.2794)
						)
					)
					(width 0)
					(fill yes)
				)
			)
		)
		(pad "2" smd custom
			(at 0 0.4445 270)
			(size 0.1397 0.1397)
			(layers "F.Cu" "F.Mask" "F.Paste")
			(net "SDB_RX")
			(options
				(clearance outline)
				(anchor circle)
			)
			(primitives
				(gr_poly
					(pts
						(arc
							(start -0.1778 -0.2794)
							(mid -0.249642 -0.249642)
							(end -0.2794 -0.1778)
						)
						(arc
							(start -0.2794 0.1778)
							(mid -0.249642 0.249642)
							(end -0.1778 0.2794)
						)
						(arc
							(start 0.1778 0.2794)
							(mid 0.249642 0.249642)
							(end 0.2794 0.1778)
						)
						(arc
							(start 0.2794 -0.1778)
							(mid 0.249642 -0.249642)
							(end 0.1778 -0.2794)
						)
					)
					(width 0)
					(fill yes)
				)
			)
		)
	)
	(footprint ""
		(layer "F.Cu")
		(at 89.662 -21.082 180)
		(property "Reference" "PR183"
			(at 0 0 180)
			(layer "F.SilkS")
			(hide yes)
			(effects
				(font
					(size 1.27 1.27)
				)
			)
		)
		(property "Value" "1K21R2F-2-GP"
			(at 0.064008 -3.993896 180)
			(unlocked yes)
			(layer "F.Fab")
			(hide yes)
			(effects
				(font
					(size 1.016 1.016)
					(thickness 0.1524)
				)
			)
		)
		(property "Device Type" "R402H16"
			(at 0.064008 -5.517896 180)
			(unlocked yes)
			(layer "F.Fab")
			(hide yes)
			(effects
				(font
					(size 1.016 1.016)
					(thickness 0.1524)
				)
			)
		)
		(duplicate_pad_numbers_are_jumpers no)
		(fp_line
			(start 0.508 -0.9398)
			(end -0.508 -0.9398)
			(stroke
				(width 0.1524)
				(type default)
			)
			(layer "F.SilkS")
		)
		(fp_line
			(start -0.508 -0.9398)
			(end -0.508 0.9398)
			(stroke
				(width 0.1524)
				(type default)
			)
			(layer "F.SilkS")
		)
		(fp_rect
			(start -0.508 0.9398)
			(end 0.508 -0.9398)
			(stroke
				(width 0)
				(type default)
			)
			(fill no)
			(layer "F.CrtYd")
		)
		(fp_rect
			(start -0.508 0.9398)
			(end 0.508 -0.9398)
			(stroke
				(width 0)
				(type default)
			)
			(fill no)
			(layer "F.Fab")
		)
		(pad "1" smd custom
			(at 0 -0.4445 180)
			(size 0.1397 0.1397)
			(layers "F.Cu" "F.Mask" "F.Paste")
			(net "VT235_VFB")
			(options
				(clearance outline)
				(anchor circle)
			)
			(primitives
				(gr_poly
					(pts
						(arc
							(start -0.1778 -0.2794)
							(mid -0.249642 -0.249642)
							(end -0.2794 -0.1778)
						)
						(arc
							(start -0.2794 0.1778)
							(mid -0.249642 0.249642)
							(end -0.1778 0.2794)
						)
						(arc
							(start 0.1778 0.2794)
							(mid 0.249642 0.249642)
							(end 0.2794 0.1778)
						)
						(arc
							(start 0.2794 -0.1778)
							(mid 0.249642 -0.249642)
							(end 0.1778 -0.2794)
						)
					)
					(width 0)
					(fill yes)
				)
			)
		)
		(pad "2" smd custom
			(at 0 0.4445 180)
			(size 0.1397 0.1397)
			(layers "F.Cu" "F.Mask" "F.Paste")
			(net "VT235_VDES_RC")
			(options
				(clearance outline)
				(anchor circle)
			)
			(primitives
				(gr_poly
					(pts
						(arc
							(start -0.1778 -0.2794)
							(mid -0.249642 -0.249642)
							(end -0.2794 -0.1778)
						)
						(arc
							(start -0.2794 0.1778)
							(mid -0.249642 0.249642)
							(end -0.1778 0.2794)
						)
						(arc
							(start 0.1778 0.2794)
							(mid 0.249642 0.249642)
							(end 0.2794 0.1778)
						)
						(arc
							(start 0.2794 -0.1778)
							(mid 0.249642 -0.249642)
							(end 0.1778 -0.2794)
						)
					)
					(width 0)
					(fill yes)
				)
			)
		)
	)
	(footprint ""
		(layer "F.Cu")
		(at 291.964872 -223.592136 180)
		(property "Reference" "PC83"
			(at 0 0 180)
			(layer "F.SilkS")
			(hide yes)
			(effects
				(font
					(size 1.27 1.27)
				)
			)
		)
		(property "Value" "SC10U6D3V5KX-1GP"
			(at -0.0762 -6.1214 180)
			(unlocked yes)
			(layer "F.Fab")
			(hide yes)
			(effects
				(font
					(size 1.016 1.016)
					(thickness 0.1524)
				)
			)
		)
		(property "Device Type" "C805H54"
			(at -0.0762 -8.1534 180)
			(unlocked yes)
			(layer "F.Fab")
			(hide yes)
			(effects
				(font
					(size 1.016 1.016)
					(thickness 0.1524)
				)
			)
		)
		(duplicate_pad_numbers_are_jumpers no)
		(fp_line
			(start 0.635 0)
			(end -0.635 0)
			(stroke
				(width 0.508)
				(type default)
			)
			(layer "F.SilkS")
		)
		(fp_rect
			(start -0.9652 1.778)
			(end 0.9652 -1.778)
			(stroke
				(width 0)
				(type default)
			)
			(fill no)
			(layer "F.CrtYd")
		)
		(fp_poly
			(pts
				(xy -0.9652 -1.778) (xy 0.9652 -1.778) (xy 0.9652 1.778) (xy -0.9652 1.778)
			)
			(stroke
				(width 0)
				(type default)
			)
			(fill no)
			(layer "F.Fab")
		)
		(pad "1" smd rect
			(at 0 -0.9652 180)
			(size 1.397 1.143)
			(layers "F.Cu" "F.Mask" "F.Paste")
			(net "TPS74801_1V53_STBY_OUT")
		)
		(pad "2" smd rect
			(at 0 0.9652 180)
			(size 1.397 1.143)
			(layers "F.Cu" "F.Mask" "F.Paste")
			(net "GND")
		)
	)
	(footprint ""
		(layer "F.Cu")
		(at 10.110216 -237.29188)
		(property "Reference" "SC430"
			(at 0 0 0)
			(layer "F.SilkS")
			(hide yes)
			(effects
				(font
					(size 1.27 1.27)
				)
			)
		)
		(property "Value" "SC1U10V3KX-4GP-U"
			(at 0 -2.8194 0)
			(unlocked yes)
			(layer "F.Fab")
			(hide yes)
			(effects
				(font
					(size 1.016 1.016)
					(thickness 0.1524)
				)
			)
		)
		(property "Device Type" "C603H36"
			(at 0 -4.3434 0)
			(unlocked yes)
			(layer "F.Fab")
			(hide yes)
			(effects
				(font
					(size 1.016 1.016)
					(thickness 0.1524)
				)
			)
		)
		(duplicate_pad_numbers_are_jumpers no)
		(fp_line
			(start 0.508 0)
			(end -0.508 0)
			(stroke
				(width 0.2032)
				(type default)
			)
			(layer "F.SilkS")
		)
		(fp_rect
			(start -0.5842 1.3335)
			(end 0.5842 -1.3335)
			(stroke
				(width 0)
				(type default)
			)
			(fill no)
			(layer "F.CrtYd")
		)
		(fp_rect
			(start -0.5842 1.3335)
			(end 0.5842 -1.3335)
			(stroke
				(width 0)
				(type default)
			)
			(fill no)
			(layer "F.Fab")
		)
		(pad "1" smd custom
			(at 0 -0.762)
			(size 0.2159 0.2159)
			(layers "F.Cu" "F.Mask" "F.Paste")
			(net "GND")
			(options
				(clearance outline)
				(anchor circle)
			)
			(primitives
				(gr_poly
					(pts
						(arc
							(start -0.3302 -0.4318)
							(mid -0.402042 -0.402042)
							(end -0.4318 -0.3302)
						)
						(arc
							(start -0.4318 0.3302)
							(mid -0.402042 0.402042)
							(end -0.3302 0.4318)
						)
						(arc
							(start 0.3302 0.4318)
							(mid 0.402042 0.402042)
							(end 0.4318 0.3302)
						)
						(arc
							(start 0.4318 -0.3302)
							(mid 0.402042 -0.402042)
							(end 0.3302 -0.4318)
						)
					)
					(width 0)
					(fill yes)
				)
			)
		)
		(pad "2" smd custom
			(at 0 0.762)
			(size 0.2159 0.2159)
			(layers "F.Cu" "F.Mask" "F.Paste")
			(net "P3V3_STBY")
			(options
				(clearance outline)
				(anchor circle)
			)
			(primitives
				(gr_poly
					(pts
						(arc
							(start -0.3302 -0.4318)
							(mid -0.402042 -0.402042)
							(end -0.4318 -0.3302)
						)
						(arc
							(start -0.4318 0.3302)
							(mid -0.402042 0.402042)
							(end -0.3302 0.4318)
						)
						(arc
							(start 0.3302 0.4318)
							(mid 0.402042 0.402042)
							(end 0.4318 0.3302)
						)
						(arc
							(start 0.4318 -0.3302)
							(mid 0.402042 -0.402042)
							(end 0.3302 -0.4318)
						)
					)
					(width 0)
					(fill yes)
				)
			)
		)
	)
	(footprint ""
		(layer "F.Cu")
		(at 306.959 -109.855 -90)
		(property "Reference" "C5"
			(at 0 0 270)
			(layer "F.SilkS")
			(hide yes)
			(effects
				(font
					(size 1.27 1.27)
				)
			)
		)
		(property "Value" "SCD1U16V2KX-3GP"
			(at 1.1811 -2.7051 270)
			(unlocked yes)
			(layer "F.Fab")
			(hide yes)
			(effects
				(font
					(size 1.016 1.016)
					(thickness 0.1524)
				)
			)
		)
		(property "Device Type" "C402H22"
			(at 1.1811 -4.2291 270)
			(unlocked yes)
			(layer "F.Fab")
			(hide yes)
			(effects
				(font
					(size 1.016 1.016)
					(thickness 0.1524)
				)
			)
		)
		(duplicate_pad_numbers_are_jumpers no)
		(fp_rect
			(start -0.4318 0.9525)
			(end 0.4318 -0.9525)
			(stroke
				(width 0)
				(type default)
			)
			(fill no)
			(layer "F.CrtYd")
		)
		(fp_rect
			(start -0.4318 0.9525)
			(end 0.4318 -0.9525)
			(stroke
				(width 0)
				(type default)
			)
			(fill no)
			(layer "F.Fab")
		)
		(pad "1" smd custom
			(at 0 -0.4445 270)
			(size 0.1524 0.1524)
			(layers "F.Cu" "F.Mask" "F.Paste")
			(net "P3V3_STBY")
			(options
				(clearance outline)
				(anchor circle)
			)
			(primitives
				(gr_poly
					(pts
						(arc
							(start 0.3048 -0.2032)
							(mid 0.275042 -0.275042)
							(end 0.2032 -0.3048)
						)
						(arc
							(start -0.2032 -0.3048)
							(mid -0.275042 -0.275042)
							(end -0.3048 -0.2032)
						)
						(arc
							(start -0.3048 0.2032)
							(mid -0.275042 0.275042)
							(end -0.2032 0.3048)
						)
						(arc
							(start 0.2032 0.3048)
							(mid 0.275042 0.275042)
							(end 0.3048 0.2032)
						)
					)
					(width 0)
					(fill yes)
				)
			)
		)
		(pad "2" smd custom
			(at 0 0.4445 270)
			(size 0.1524 0.1524)
			(layers "F.Cu" "F.Mask" "F.Paste")
			(net "GND")
			(options
				(clearance outline)
				(anchor circle)
			)
			(primitives
				(gr_poly
					(pts
						(arc
							(start 0.3048 -0.2032)
							(mid 0.275042 -0.275042)
							(end 0.2032 -0.3048)
						)
						(arc
							(start -0.2032 -0.3048)
							(mid -0.275042 -0.275042)
							(end -0.3048 -0.2032)
						)
						(arc
							(start -0.3048 0.2032)
							(mid -0.275042 0.275042)
							(end -0.2032 0.3048)
						)
						(arc
							(start 0.2032 0.3048)
							(mid 0.275042 0.275042)
							(end 0.3048 0.2032)
						)
					)
					(width 0)
					(fill yes)
				)
			)
		)
	)
	(footprint ""
		(layer "F.Cu")
		(at 55.89397 -143.383 90)
		(property "Reference" "SR1277"
			(at 0 0 90)
			(layer "F.SilkS")
			(hide yes)
			(effects
				(font
					(size 1.27 1.27)
				)
			)
		)
		(property "Value" "0R2J-2-GP"
			(at 0.064008 -3.993896 90)
			(unlocked yes)
			(layer "F.Fab")
			(hide yes)
			(effects
				(font
					(size 1.016 1.016)
					(thickness 0.1524)
				)
			)
		)
		(property "Device Type" "R402H16"
			(at 0.064008 -5.517896 90)
			(unlocked yes)
			(layer "F.Fab")
			(hide yes)
			(effects
				(font
					(size 1.016 1.016)
					(thickness 0.1524)
				)
			)
		)
		(duplicate_pad_numbers_are_jumpers no)
		(fp_line
			(start 0.508 -0.9398)
			(end -0.508 -0.9398)
			(stroke
				(width 0.1524)
				(type default)
			)
			(layer "F.SilkS")
		)
		(fp_line
			(start -0.508 -0.9398)
			(end -0.508 0.9398)
			(stroke
				(width 0.1524)
				(type default)
			)
			(layer "F.SilkS")
		)
		(fp_rect
			(start -0.508 0.9398)
			(end 0.508 -0.9398)
			(stroke
				(width 0)
				(type default)
			)
			(fill no)
			(layer "F.CrtYd")
		)
		(fp_rect
			(start -0.508 0.9398)
			(end 0.508 -0.9398)
			(stroke
				(width 0)
				(type default)
			)
			(fill no)
			(layer "F.Fab")
		)
		(pad "1" smd custom
			(at 0 -0.4445 90)
			(size 0.1397 0.1397)
			(layers "F.Cu" "F.Mask" "F.Paste")
			(net "DP_EXP_RST")
			(options
				(clearance outline)
				(anchor circle)
			)
			(primitives
				(gr_poly
					(pts
						(arc
							(start -0.1778 -0.2794)
							(mid -0.249642 -0.249642)
							(end -0.2794 -0.1778)
						)
						(arc
							(start -0.2794 0.1778)
							(mid -0.249642 0.249642)
							(end -0.1778 0.2794)
						)
						(arc
							(start 0.1778 0.2794)
							(mid 0.249642 0.249642)
							(end 0.2794 0.1778)
						)
						(arc
							(start 0.2794 -0.1778)
							(mid 0.249642 -0.249642)
							(end 0.1778 -0.2794)
						)
					)
					(width 0)
					(fill yes)
				)
			)
		)
		(pad "2" smd custom
			(at 0 0.4445 90)
			(size 0.1397 0.1397)
			(layers "F.Cu" "F.Mask" "F.Paste")
			(net "DP_EXP_RST_R")
			(options
				(clearance outline)
				(anchor circle)
			)
			(primitives
				(gr_poly
					(pts
						(arc
							(start -0.1778 -0.2794)
							(mid -0.249642 -0.249642)
							(end -0.2794 -0.1778)
						)
						(arc
							(start -0.2794 0.1778)
							(mid -0.249642 0.249642)
							(end -0.1778 0.2794)
						)
						(arc
							(start 0.1778 0.2794)
							(mid 0.249642 0.249642)
							(end 0.2794 0.1778)
						)
						(arc
							(start 0.2794 -0.1778)
							(mid 0.249642 -0.249642)
							(end 0.1778 -0.2794)
						)
					)
					(width 0)
					(fill yes)
				)
			)
		)
	)
	(footprint ""
		(layer "F.Cu")
		(at 197.039992 -46.355 180)
		(property "Reference" "R521"
			(at 0 0 180)
			(layer "F.SilkS")
			(hide yes)
			(effects
				(font
					(size 1.27 1.27)
				)
			)
		)
		(property "Value" "10KR2F-2-GP"
			(at 0.064008 -3.993896 180)
			(unlocked yes)
			(layer "F.Fab")
			(hide yes)
			(effects
				(font
					(size 1.016 1.016)
					(thickness 0.1524)
				)
			)
		)
		(property "Device Type" "R402H16"
			(at 0.064008 -5.517896 180)
			(unlocked yes)
			(layer "F.Fab")
			(hide yes)
			(effects
				(font
					(size 1.016 1.016)
					(thickness 0.1524)
				)
			)
		)
		(duplicate_pad_numbers_are_jumpers no)
		(fp_line
			(start 0.508 -0.9398)
			(end -0.508 -0.9398)
			(stroke
				(width 0.1524)
				(type default)
			)
			(layer "F.SilkS")
		)
		(fp_line
			(start -0.508 -0.9398)
			(end -0.508 0.9398)
			(stroke
				(width 0.1524)
				(type default)
			)
			(layer "F.SilkS")
		)
		(fp_rect
			(start -0.508 0.9398)
			(end 0.508 -0.9398)
			(stroke
				(width 0)
				(type default)
			)
			(fill no)
			(layer "F.CrtYd")
		)
		(fp_rect
			(start -0.508 0.9398)
			(end 0.508 -0.9398)
			(stroke
				(width 0)
				(type default)
			)
			(fill no)
			(layer "F.Fab")
		)
		(pad "1" smd custom
			(at 0 -0.4445 180)
			(size 0.1397 0.1397)
			(layers "F.Cu" "F.Mask" "F.Paste")
			(net "PRSNT_MSB_B81")
			(options
				(clearance outline)
				(anchor circle)
			)
			(primitives
				(gr_poly
					(pts
						(arc
							(start -0.1778 -0.2794)
							(mid -0.249642 -0.249642)
							(end -0.2794 -0.1778)
						)
						(arc
							(start -0.2794 0.1778)
							(mid -0.249642 0.249642)
							(end -0.1778 0.2794)
						)
						(arc
							(start 0.1778 0.2794)
							(mid 0.249642 0.249642)
							(end 0.2794 0.1778)
						)
						(arc
							(start 0.2794 -0.1778)
							(mid 0.249642 -0.249642)
							(end 0.1778 -0.2794)
						)
					)
					(width 0)
					(fill yes)
				)
			)
		)
		(pad "2" smd custom
			(at 0 0.4445 180)
			(size 0.1397 0.1397)
			(layers "F.Cu" "F.Mask" "F.Paste")
			(net "P3V3_STBY")
			(options
				(clearance outline)
				(anchor circle)
			)
			(primitives
				(gr_poly
					(pts
						(arc
							(start -0.1778 -0.2794)
							(mid -0.249642 -0.249642)
							(end -0.2794 -0.1778)
						)
						(arc
							(start -0.2794 0.1778)
							(mid -0.249642 0.249642)
							(end -0.1778 0.2794)
						)
						(arc
							(start 0.1778 0.2794)
							(mid 0.249642 0.249642)
							(end 0.2794 0.1778)
						)
						(arc
							(start 0.2794 -0.1778)
							(mid 0.249642 -0.249642)
							(end 0.1778 -0.2794)
						)
					)
					(width 0)
					(fill yes)
				)
			)
		)
	)
	(footprint ""
		(layer "F.Cu")
		(at 329.057 -8.255)
		(property "Reference" "R458"
			(at 0 0 0)
			(layer "F.SilkS")
			(hide yes)
			(effects
				(font
					(size 1.27 1.27)
				)
			)
		)
		(property "Value" "33R2J-2-GP"
			(at 0.064008 -3.993896 0)
			(unlocked yes)
			(layer "F.Fab")
			(hide yes)
			(effects
				(font
					(size 1.016 1.016)
					(thickness 0.1524)
				)
			)
		)
		(property "Device Type" "R402H16"
			(at 0.064008 -5.517896 0)
			(unlocked yes)
			(layer "F.Fab")
			(hide yes)
			(effects
				(font
					(size 1.016 1.016)
					(thickness 0.1524)
				)
			)
		)
		(duplicate_pad_numbers_are_jumpers no)
		(fp_line
			(start -0.508 -0.9398)
			(end -0.508 0.9398)
			(stroke
				(width 0.1524)
				(type default)
			)
			(layer "F.SilkS")
		)
		(fp_line
			(start 0.508 -0.9398)
			(end -0.508 -0.9398)
			(stroke
				(width 0.1524)
				(type default)
			)
			(layer "F.SilkS")
		)
		(fp_rect
			(start -0.508 0.9398)
			(end 0.508 -0.9398)
			(stroke
				(width 0)
				(type default)
			)
			(fill no)
			(layer "F.CrtYd")
		)
		(fp_rect
			(start -0.508 0.9398)
			(end 0.508 -0.9398)
			(stroke
				(width 0)
				(type default)
			)
			(fill no)
			(layer "F.Fab")
		)
		(pad "1" smd custom
			(at 0 -0.4445)
			(size 0.1397 0.1397)
			(layers "F.Cu" "F.Mask" "F.Paste")
			(net "GND")
			(options
				(clearance outline)
				(anchor circle)
			)
			(primitives
				(gr_poly
					(pts
						(arc
							(start -0.1778 -0.2794)
							(mid -0.249642 -0.249642)
							(end -0.2794 -0.1778)
						)
						(arc
							(start -0.2794 0.1778)
							(mid -0.249642 0.249642)
							(end -0.1778 0.2794)
						)
						(arc
							(start 0.1778 0.2794)
							(mid 0.249642 0.249642)
							(end 0.2794 0.1778)
						)
						(arc
							(start 0.2794 -0.1778)
							(mid 0.249642 -0.249642)
							(end 0.1778 -0.2794)
						)
					)
					(width 0)
					(fill yes)
				)
			)
		)
		(pad "2" smd custom
			(at 0 0.4445)
			(size 0.1397 0.1397)
			(layers "F.Cu" "F.Mask" "F.Paste")
			(net "DEBUG_PORT_GND")
			(options
				(clearance outline)
				(anchor circle)
			)
			(primitives
				(gr_poly
					(pts
						(arc
							(start -0.1778 -0.2794)
							(mid -0.249642 -0.249642)
							(end -0.2794 -0.1778)
						)
						(arc
							(start -0.2794 0.1778)
							(mid -0.249642 0.249642)
							(end -0.1778 0.2794)
						)
						(arc
							(start 0.1778 0.2794)
							(mid 0.249642 0.249642)
							(end 0.2794 0.1778)
						)
						(arc
							(start 0.2794 -0.1778)
							(mid 0.249642 -0.249642)
							(end 0.1778 -0.2794)
						)
					)
					(width 0)
					(fill yes)
				)
			)
		)
	)
)
